(kicad_pcb
	(version 20260206)
	(generator "pcbnew")
	(generator_version "10.0")
	(general
		(thickness 1.6)
		(legacy_teardrops no)
	)
	(paper "A4")
	(title_block
		(title "Bryce Canyon_IOM_M2_16342-2_OCP.brd")
		(comment 1 "Bryce Canyon / footprints 1082-1090 of 1146")
	)
	(layers
		(0 "F.Cu" signal "TOP")
		(4 "In1.Cu" signal "L2GND")
		(6 "In2.Cu" signal "L3")
		(8 "In3.Cu" signal "L4VCC")
		(10 "In4.Cu" signal "L5VCC")
		(12 "In5.Cu" signal "L6")
		(14 "In6.Cu" signal "L7GND")
		(2 "B.Cu" signal "BOTTOM")
		(9 "F.Adhes" user "F.Adhesive")
		(11 "B.Adhes" user "B.Adhesive")
		(13 "F.Paste" user "Package Geometry/Pastemask Top")
		(15 "B.Paste" user "Package Geometry/Pastemask Bottom")
		(5 "F.SilkS" user "Ref Des/Silkscreen Top")
		(7 "B.SilkS" user "Ref Des/Silkscreen Bottom")
		(1 "F.Mask" user "Board Geometry/Soldermask Top")
		(3 "B.Mask" user "Board Geometry/Soldermask Bottom")
		(17 "Dwgs.User" user "User.Drawings")
		(19 "Cmts.User" user "User.Comments")
		(21 "Eco1.User" user "User.Eco1")
		(23 "Eco2.User" user "User.Eco2")
		(25 "Edge.Cuts" user "Board Geometry/Outline")
		(27 "Margin" user)
		(31 "F.CrtYd" user "Package Geometry/Place Bound Top")
		(29 "B.CrtYd" user "Package Geometry/Place Bound Bottom")
		(35 "F.Fab" user "Ref Des/Assembly Top")
		(33 "B.Fab" user "Ref Des/Assembly Bottom")
	)
	(footprint ""
		(layer "B.Cu")
		(at 69.3166 -148.844)
		(property "Reference" "R381"
			(at 0 0 0)
			(layer "B.SilkS")
			(hide yes)
			(effects
				(font
					(size 1.27 1.27)
				)
				(justify mirror)
			)
		)
		(property "Value" "4K7R2F-GP"
			(at -0.064008 -3.993896 0)
			(unlocked yes)
			(layer "B.Fab")
			(hide yes)
			(effects
				(font
					(size 1.016 1.016)
					(thickness 0.1524)
				)
				(justify mirror)
			)
		)
		(property "Device Type" "R402H16"
			(at -0.064008 -5.517896 0)
			(unlocked yes)
			(layer "B.Fab")
			(hide yes)
			(effects
				(font
					(size 1.016 1.016)
					(thickness 0.1524)
				)
				(justify mirror)
			)
		)
		(duplicate_pad_numbers_are_jumpers no)
		(fp_line
			(start -0.508 -0.9398)
			(end 0.508 -0.9398)
			(stroke
				(width 0.1524)
				(type default)
			)
			(layer "B.SilkS")
		)
		(fp_line
			(start 0.508 -0.9398)
			(end 0.508 0.9398)
			(stroke
				(width 0.1524)
				(type default)
			)
			(layer "B.SilkS")
		)
		(fp_rect
			(start 0.508 0.9398)
			(end -0.508 -0.9398)
			(stroke
				(width 0)
				(type default)
			)
			(fill no)
			(layer "B.CrtYd")
		)
		(fp_rect
			(start 0.508 0.9398)
			(end -0.508 -0.9398)
			(stroke
				(width 0)
				(type default)
			)
			(fill no)
			(layer "B.Fab")
		)
		(pad "1" smd custom
			(at 0 -0.4445 180)
			(size 0.1397 0.1397)
			(layers "B.Cu" "B.Mask" "B.Paste")
			(net "P3V3_STBY")
			(options
				(clearance outline)
				(anchor circle)
			)
			(primitives
				(gr_poly
					(pts
						(arc
							(start -0.1778 0.2794)
							(mid -0.249642 0.249642)
							(end -0.2794 0.1778)
						)
						(arc
							(start -0.2794 -0.1778)
							(mid -0.249642 -0.249642)
							(end -0.1778 -0.2794)
						)
						(arc
							(start 0.1778 -0.2794)
							(mid 0.249642 -0.249642)
							(end 0.2794 -0.1778)
						)
						(arc
							(start 0.2794 0.1778)
							(mid 0.249642 0.249642)
							(end 0.1778 0.2794)
						)
					)
					(width 0)
					(fill yes)
				)
			)
		)
		(pad "2" smd custom
			(at 0 0.4445 180)
			(size 0.1397 0.1397)
			(layers "B.Cu" "B.Mask" "B.Paste")
			(net "NCSI_TXD0")
			(options
				(clearance outline)
				(anchor circle)
			)
			(primitives
				(gr_poly
					(pts
						(arc
							(start -0.1778 0.2794)
							(mid -0.249642 0.249642)
							(end -0.2794 0.1778)
						)
						(arc
							(start -0.2794 -0.1778)
							(mid -0.249642 -0.249642)
							(end -0.1778 -0.2794)
						)
						(arc
							(start 0.1778 -0.2794)
							(mid 0.249642 -0.249642)
							(end 0.2794 -0.1778)
						)
						(arc
							(start 0.2794 0.1778)
							(mid 0.249642 0.249642)
							(end 0.1778 0.2794)
						)
					)
					(width 0)
					(fill yes)
				)
			)
		)
	)
	(footprint ""
		(layer "B.Cu")
		(at 24.4602 -179.2478 -90)
		(property "Reference" "C179"
			(at 0 0 90)
			(layer "B.SilkS")
			(hide yes)
			(effects
				(font
					(size 1.27 1.27)
				)
				(justify mirror)
			)
		)
		(property "Value" "SC4D7U25V5KX-1-GP"
			(at 0.0762 -6.1214 270)
			(unlocked yes)
			(layer "B.Fab")
			(hide yes)
			(effects
				(font
					(size 1.016 1.016)
					(thickness 0.1524)
				)
				(justify mirror)
			)
		)
		(property "Device Type" "C805H58"
			(at 0.0762 -8.1534 270)
			(unlocked yes)
			(layer "B.Fab")
			(hide yes)
			(effects
				(font
					(size 1.016 1.016)
					(thickness 0.1524)
				)
				(justify mirror)
			)
		)
		(duplicate_pad_numbers_are_jumpers no)
		(fp_line
			(start -0.635 0)
			(end 0.635 0)
			(stroke
				(width 0.508)
				(type default)
			)
			(layer "B.SilkS")
		)
		(fp_rect
			(start 0.9652 1.778)
			(end -0.9652 -1.778)
			(stroke
				(width 0)
				(type default)
			)
			(fill no)
			(layer "B.CrtYd")
		)
		(fp_poly
			(pts
				(xy 0.9652 -1.778) (xy -0.9652 -1.778) (xy -0.9652 1.778) (xy 0.9652 1.778)
			)
			(stroke
				(width 0)
				(type default)
			)
			(fill no)
			(layer "B.Fab")
		)
		(pad "1" smd rect
			(at 0 -0.9652 90)
			(size 1.397 1.143)
			(layers "B.Cu" "B.Mask" "B.Paste")
			(net "P12V_STBY_VDD_PU2")
		)
		(pad "2" smd rect
			(at 0 0.9652 90)
			(size 1.397 1.143)
			(layers "B.Cu" "B.Mask" "B.Paste")
			(net "GND")
		)
	)
	(footprint ""
		(layer "B.Cu")
		(at 95.25 -6.223 90)
		(property "Reference" "C525"
			(at 0 0 90)
			(layer "B.SilkS")
			(hide yes)
			(effects
				(font
					(size 1.27 1.27)
				)
				(justify mirror)
			)
		)
		(property "Value" "SC1000P2KV6KX-GP-U"
			(at -0.0508 -3.5052 90)
			(unlocked yes)
			(layer "B.Fab")
			(hide yes)
			(effects
				(font
					(size 1.016 1.016)
					(thickness 0.1524)
				)
				(justify mirror)
			)
		)
		(property "Device Type" "C1206H58"
			(at -0.0508 -5.0292 90)
			(unlocked yes)
			(layer "B.Fab")
			(hide yes)
			(effects
				(font
					(size 1.016 1.016)
					(thickness 0.1524)
				)
				(justify mirror)
			)
		)
		(duplicate_pad_numbers_are_jumpers no)
		(fp_line
			(start 1.016 -2.2352)
			(end 1.016 -0.8382)
			(stroke
				(width 0.1524)
				(type default)
			)
			(layer "B.SilkS")
		)
		(fp_line
			(start -1.016 -2.2352)
			(end 1.016 -2.2352)
			(stroke
				(width 0.1524)
				(type default)
			)
			(layer "B.SilkS")
		)
		(fp_line
			(start -1.016 -2.2352)
			(end -1.016 -0.8382)
			(stroke
				(width 0.1524)
				(type default)
			)
			(layer "B.SilkS")
		)
		(fp_line
			(start -1.016 0.8382)
			(end -1.016 2.2352)
			(stroke
				(width 0.1524)
				(type default)
			)
			(layer "B.SilkS")
		)
		(fp_line
			(start 1.016 2.2352)
			(end 1.016 0.8128)
			(stroke
				(width 0.1524)
				(type default)
			)
			(layer "B.SilkS")
		)
		(fp_line
			(start -1.016 2.2352)
			(end 1.016 2.2352)
			(stroke
				(width 0.1524)
				(type default)
			)
			(layer "B.SilkS")
		)
		(fp_rect
			(start 1.0922 2.3114)
			(end -1.0922 -2.3114)
			(stroke
				(width 0)
				(type default)
			)
			(fill no)
			(layer "B.CrtYd")
		)
		(fp_poly
			(pts
				(xy 1.0922 -2.3114) (xy -1.0922 -2.3114) (xy -1.0922 2.3114) (xy 1.0922 2.3114)
			)
			(stroke
				(width 0)
				(type default)
			)
			(fill no)
			(layer "B.Fab")
		)
		(pad "1" smd rect
			(at 0 -1.397 270)
			(size 1.651 1.27)
			(layers "B.Cu" "B.Mask" "B.Paste")
			(net "USB_CONN_GND")
		)
		(pad "2" smd rect
			(at 0 1.397 270)
			(size 1.651 1.27)
			(layers "B.Cu" "B.Mask" "B.Paste")
			(net "GND")
		)
	)
	(footprint ""
		(layer "B.Cu")
		(at 56.3118 -138.557 -90)
		(property "Reference" "TP70"
			(at 0 0 90)
			(layer "B.SilkS")
			(hide yes)
			(effects
				(font
					(size 1.27 1.27)
				)
				(justify mirror)
			)
		)
		(property "Value" "TPAD28-2-GP"
			(at 0.0127 -1.6637 270)
			(unlocked yes)
			(layer "B.Fab")
			(hide yes)
			(effects
				(font
					(size 1.016 1.016)
					(thickness 0.1524)
				)
				(justify mirror)
			)
		)
		(property "Device Type" "TPAD28"
			(at 0.0127 -3.1877 270)
			(unlocked yes)
			(layer "B.Fab")
			(hide yes)
			(effects
				(font
					(size 1.016 1.016)
					(thickness 0.1524)
				)
				(justify mirror)
			)
		)
		(duplicate_pad_numbers_are_jumpers no)
		(fp_poly
			(pts
				(arc
					(start 0 -0.3556)
					(mid 0 0.3556)
					(end 0 -0.3556)
				)
			)
			(stroke
				(width 0)
				(type default)
			)
			(fill no)
			(layer "B.CrtYd")
		)
		(fp_poly
			(pts
				(arc
					(start 0 -0.6096)
					(mid 0 0.6096)
					(end 0 -0.6096)
				)
			)
			(stroke
				(width 0)
				(type default)
			)
			(fill no)
			(layer "B.Fab")
		)
		(pad "1" smd circle
			(at 0 0 90)
			(size 0.7112 0.7112)
			(layers "B.Cu" "B.Mask" "B.Paste")
			(net "TP_BMC_GPIOI0")
		)
	)
	(footprint ""
		(layer "B.Cu")
		(at 20.376896 -141.833092 -90)
		(property "Reference" "R205"
			(at 0 0 90)
			(layer "B.SilkS")
			(hide yes)
			(effects
				(font
					(size 1.27 1.27)
				)
				(justify mirror)
			)
		)
		(property "Value" "60D4R2F-GP"
			(at -0.064008 -3.993896 270)
			(unlocked yes)
			(layer "B.Fab")
			(hide yes)
			(effects
				(font
					(size 1.016 1.016)
					(thickness 0.1524)
				)
				(justify mirror)
			)
		)
		(property "Device Type" "R402H16"
			(at -0.064008 -5.517896 270)
			(unlocked yes)
			(layer "B.Fab")
			(hide yes)
			(effects
				(font
					(size 1.016 1.016)
					(thickness 0.1524)
				)
				(justify mirror)
			)
		)
		(duplicate_pad_numbers_are_jumpers no)
		(fp_line
			(start -0.508 -0.9398)
			(end 0.508 -0.9398)
			(stroke
				(width 0.1524)
				(type default)
			)
			(layer "B.SilkS")
		)
		(fp_line
			(start 0.508 -0.9398)
			(end 0.508 0.9398)
			(stroke
				(width 0.1524)
				(type default)
			)
			(layer "B.SilkS")
		)
		(fp_rect
			(start 0.508 0.9398)
			(end -0.508 -0.9398)
			(stroke
				(width 0)
				(type default)
			)
			(fill no)
			(layer "B.CrtYd")
		)
		(fp_rect
			(start 0.508 0.9398)
			(end -0.508 -0.9398)
			(stroke
				(width 0)
				(type default)
			)
			(fill no)
			(layer "B.Fab")
		)
		(pad "1" smd custom
			(at 0 -0.4445 90)
			(size 0.1397 0.1397)
			(layers "B.Cu" "B.Mask" "B.Paste")
			(net "MEMCK_P")
			(options
				(clearance outline)
				(anchor circle)
			)
			(primitives
				(gr_poly
					(pts
						(arc
							(start -0.1778 0.2794)
							(mid -0.249642 0.249642)
							(end -0.2794 0.1778)
						)
						(arc
							(start -0.2794 -0.1778)
							(mid -0.249642 -0.249642)
							(end -0.1778 -0.2794)
						)
						(arc
							(start 0.1778 -0.2794)
							(mid 0.249642 -0.249642)
							(end 0.2794 -0.1778)
						)
						(arc
							(start 0.2794 0.1778)
							(mid 0.249642 0.249642)
							(end 0.1778 0.2794)
						)
					)
					(width 0)
					(fill yes)
				)
			)
		)
		(pad "2" smd custom
			(at 0 0.4445 90)
			(size 0.1397 0.1397)
			(layers "B.Cu" "B.Mask" "B.Paste")
			(net "MEMCK_TER")
			(options
				(clearance outline)
				(anchor circle)
			)
			(primitives
				(gr_poly
					(pts
						(arc
							(start -0.1778 0.2794)
							(mid -0.249642 0.249642)
							(end -0.2794 0.1778)
						)
						(arc
							(start -0.2794 -0.1778)
							(mid -0.249642 -0.249642)
							(end -0.1778 -0.2794)
						)
						(arc
							(start 0.1778 -0.2794)
							(mid 0.249642 -0.249642)
							(end 0.2794 -0.1778)
						)
						(arc
							(start 0.2794 0.1778)
							(mid 0.249642 0.249642)
							(end 0.1778 0.2794)
						)
					)
					(width 0)
					(fill yes)
				)
			)
		)
	)
	(footprint ""
		(layer "B.Cu")
		(at 176.5554 -115.57 -90)
		(property "Reference" "R834"
			(at 0 0 90)
			(layer "B.SilkS")
			(hide yes)
			(effects
				(font
					(size 1.27 1.27)
				)
				(justify mirror)
			)
		)
		(property "Value" "200KR2F-L-GP"
			(at -0.064008 -3.993896 270)
			(unlocked yes)
			(layer "B.Fab")
			(hide yes)
			(effects
				(font
					(size 1.016 1.016)
					(thickness 0.1524)
				)
				(justify mirror)
			)
		)
		(property "Device Type" "R402H16"
			(at -0.064008 -5.517896 270)
			(unlocked yes)
			(layer "B.Fab")
			(hide yes)
			(effects
				(font
					(size 1.016 1.016)
					(thickness 0.1524)
				)
				(justify mirror)
			)
		)
		(duplicate_pad_numbers_are_jumpers no)
		(fp_line
			(start -0.508 -0.9398)
			(end 0.508 -0.9398)
			(stroke
				(width 0.1524)
				(type default)
			)
			(layer "B.SilkS")
		)
		(fp_line
			(start 0.508 -0.9398)
			(end 0.508 0.9398)
			(stroke
				(width 0.1524)
				(type default)
			)
			(layer "B.SilkS")
		)
		(fp_rect
			(start 0.508 0.9398)
			(end -0.508 -0.9398)
			(stroke
				(width 0)
				(type default)
			)
			(fill no)
			(layer "B.CrtYd")
		)
		(fp_rect
			(start 0.508 0.9398)
			(end -0.508 -0.9398)
			(stroke
				(width 0)
				(type default)
			)
			(fill no)
			(layer "B.Fab")
		)
		(pad "1" smd custom
			(at 0 -0.4445 90)
			(size 0.1397 0.1397)
			(layers "B.Cu" "B.Mask" "B.Paste")
			(net "U83_VREF2")
			(options
				(clearance outline)
				(anchor circle)
			)
			(primitives
				(gr_poly
					(pts
						(arc
							(start -0.1778 0.2794)
							(mid -0.249642 0.249642)
							(end -0.2794 0.1778)
						)
						(arc
							(start -0.2794 -0.1778)
							(mid -0.249642 -0.249642)
							(end -0.1778 -0.2794)
						)
						(arc
							(start 0.1778 -0.2794)
							(mid 0.249642 -0.249642)
							(end 0.2794 -0.1778)
						)
						(arc
							(start 0.2794 0.1778)
							(mid 0.249642 0.249642)
							(end 0.1778 0.2794)
						)
					)
					(width 0)
					(fill yes)
				)
			)
		)
		(pad "2" smd custom
			(at 0 0.4445 90)
			(size 0.1397 0.1397)
			(layers "B.Cu" "B.Mask" "B.Paste")
			(net "P3V3_STBY")
			(options
				(clearance outline)
				(anchor circle)
			)
			(primitives
				(gr_poly
					(pts
						(arc
							(start -0.1778 0.2794)
							(mid -0.249642 0.249642)
							(end -0.2794 0.1778)
						)
						(arc
							(start -0.2794 -0.1778)
							(mid -0.249642 -0.249642)
							(end -0.1778 -0.2794)
						)
						(arc
							(start 0.1778 -0.2794)
							(mid 0.249642 -0.249642)
							(end 0.2794 -0.1778)
						)
						(arc
							(start 0.2794 0.1778)
							(mid 0.249642 0.249642)
							(end 0.1778 0.2794)
						)
					)
					(width 0)
					(fill yes)
				)
			)
		)
	)
	(footprint ""
		(layer "B.Cu")
		(at 227.094288 -101.96195 180)
		(property "Reference" "C638"
			(at 0 0 0)
			(layer "B.SilkS")
			(hide yes)
			(effects
				(font
					(size 1.27 1.27)
				)
				(justify mirror)
			)
		)
		(property "Value" "SC10U16V5KX-7-GP-U"
			(at 0.0762 -6.1214 180)
			(unlocked yes)
			(layer "B.Fab")
			(hide yes)
			(effects
				(font
					(size 1.016 1.016)
					(thickness 0.1524)
				)
				(justify mirror)
			)
		)
		(property "Device Type" "C805H58"
			(at 0.0762 -8.1534 180)
			(unlocked yes)
			(layer "B.Fab")
			(hide yes)
			(effects
				(font
					(size 1.016 1.016)
					(thickness 0.1524)
				)
				(justify mirror)
			)
		)
		(duplicate_pad_numbers_are_jumpers no)
		(fp_line
			(start -0.635 0)
			(end 0.635 0)
			(stroke
				(width 0.508)
				(type default)
			)
			(layer "B.SilkS")
		)
		(fp_rect
			(start 0.9652 1.778)
			(end -0.9652 -1.778)
			(stroke
				(width 0)
				(type default)
			)
			(fill no)
			(layer "B.CrtYd")
		)
		(fp_poly
			(pts
				(xy 0.9652 -1.778) (xy -0.9652 -1.778) (xy -0.9652 1.778) (xy 0.9652 1.778)
			)
			(stroke
				(width 0)
				(type default)
			)
			(fill no)
			(layer "B.Fab")
		)
		(pad "1" smd rect
			(at 0 -0.9652)
			(size 1.397 1.143)
			(layers "B.Cu" "B.Mask" "B.Paste")
			(net "P12V_STBY_VIN_U81")
		)
		(pad "2" smd rect
			(at 0 0.9652)
			(size 1.397 1.143)
			(layers "B.Cu" "B.Mask" "B.Paste")
			(net "GND")
		)
	)
	(footprint ""
		(layer "B.Cu")
		(at 41.653714 -153.965148)
		(property "Reference" "TP62"
			(at 0 0 0)
			(layer "B.SilkS")
			(hide yes)
			(effects
				(font
					(size 1.27 1.27)
				)
				(justify mirror)
			)
		)
		(property "Value" "TPAD28-2-GP"
			(at 0.0127 -1.6637 0)
			(unlocked yes)
			(layer "B.Fab")
			(hide yes)
			(effects
				(font
					(size 1.016 1.016)
					(thickness 0.1524)
				)
				(justify mirror)
			)
		)
		(property "Device Type" "TPAD28"
			(at 0.0127 -3.1877 0)
			(unlocked yes)
			(layer "B.Fab")
			(hide yes)
			(effects
				(font
					(size 1.016 1.016)
					(thickness 0.1524)
				)
				(justify mirror)
			)
		)
		(duplicate_pad_numbers_are_jumpers no)
		(fp_poly
			(pts
				(arc
					(start 0.3556 0)
					(mid -0.3556 0)
					(end 0.3556 0)
				)
			)
			(stroke
				(width 0)
				(type default)
			)
			(fill no)
			(layer "B.CrtYd")
		)
		(fp_poly
			(pts
				(arc
					(start 0.6096 0)
					(mid -0.6096 0)
					(end 0.6096 0)
				)
			)
			(stroke
				(width 0)
				(type default)
			)
			(fill no)
			(layer "B.Fab")
		)
		(pad "1" smd circle
			(at 0 0 180)
			(size 0.7112 0.7112)
			(layers "B.Cu" "B.Mask" "B.Paste")
			(net "TP_BMC_GPION2")
		)
	)
	(footprint ""
		(layer "B.Cu")
		(at 65.420494 -139.270232 -90)
		(property "Reference" "R601"
			(at 0 0 90)
			(layer "B.SilkS")
			(hide yes)
			(effects
				(font
					(size 1.27 1.27)
				)
				(justify mirror)
			)
		)
		(property "Value" "4K7R2F-GP"
			(at -0.064008 -3.993896 270)
			(unlocked yes)
			(layer "B.Fab")
			(hide yes)
			(effects
				(font
					(size 1.016 1.016)
					(thickness 0.1524)
				)
				(justify mirror)
			)
		)
		(property "Device Type" "R402H16"
			(at -0.064008 -5.517896 270)
			(unlocked yes)
			(layer "B.Fab")
			(hide yes)
			(effects
				(font
					(size 1.016 1.016)
					(thickness 0.1524)
				)
				(justify mirror)
			)
		)
		(duplicate_pad_numbers_are_jumpers no)
		(fp_line
			(start -0.508 -0.9398)
			(end 0.508 -0.9398)
			(stroke
				(width 0.1524)
				(type default)
			)
			(layer "B.SilkS")
		)
		(fp_line
			(start 0.508 -0.9398)
			(end 0.508 0.9398)
			(stroke
				(width 0.1524)
				(type default)
			)
			(layer "B.SilkS")
		)
		(fp_rect
			(start 0.508 0.9398)
			(end -0.508 -0.9398)
			(stroke
				(width 0)
				(type default)
			)
			(fill no)
			(layer "B.CrtYd")
		)
		(fp_rect
			(start 0.508 0.9398)
			(end -0.508 -0.9398)
			(stroke
				(width 0)
				(type default)
			)
			(fill no)
			(layer "B.Fab")
		)
		(pad "1" smd custom
			(at 0 -0.4445 90)
			(size 0.1397 0.1397)
			(layers "B.Cu" "B.Mask" "B.Paste")
			(net "P3V3_STBY")
			(options
				(clearance outline)
				(anchor circle)
			)
			(primitives
				(gr_poly
					(pts
						(arc
							(start -0.1778 0.2794)
							(mid -0.249642 0.249642)
							(end -0.2794 0.1778)
						)
						(arc
							(start -0.2794 -0.1778)
							(mid -0.249642 -0.249642)
							(end -0.1778 -0.2794)
						)
						(arc
							(start 0.1778 -0.2794)
							(mid 0.249642 -0.249642)
							(end 0.2794 -0.1778)
						)
						(arc
							(start 0.2794 0.1778)
							(mid 0.249642 0.249642)
							(end 0.1778 0.2794)
						)
					)
					(width 0)
					(fill yes)
				)
			)
		)
		(pad "2" smd custom
			(at 0 0.4445 90)
			(size 0.1397 0.1397)
			(layers "B.Cu" "B.Mask" "B.Paste")
			(net "I2C_COMP_ALERT_N")
			(options
				(clearance outline)
				(anchor circle)
			)
			(primitives
				(gr_poly
					(pts
						(arc
							(start -0.1778 0.2794)
							(mid -0.249642 0.249642)
							(end -0.2794 0.1778)
						)
						(arc
							(start -0.2794 -0.1778)
							(mid -0.249642 -0.249642)
							(end -0.1778 -0.2794)
						)
						(arc
							(start 0.1778 -0.2794)
							(mid 0.249642 -0.249642)
							(end 0.2794 -0.1778)
						)
						(arc
							(start 0.2794 0.1778)
							(mid 0.249642 0.249642)
							(end 0.1778 0.2794)
						)
					)
					(width 0)
					(fill yes)
				)
			)
		)
	)
)
